(kicad_pcb
	(version 20241229)
	(generator "pcbnew")
	(generator_version "9.0")
	(general
		(thickness 1.62)
		(legacy_teardrops no)
	)
	(paper "A4")
	(title_block
		(title "OCuLink to 10GbE adapter")
		(date "2026-02-23")
		(rev "1.1.0")
		(company "Antmicro Ltd")
		(comment 1 "www.antmicro.com")
		(comment 9 "footprints 351-356 of 510")
	)
	(layers
		(0 "F.Cu" signal)
		(4 "In1.Cu" signal)
		(6 "In2.Cu" signal)
		(8 "In3.Cu" signal)
		(10 "In4.Cu" signal)
		(12 "In5.Cu" signal)
		(14 "In6.Cu" signal)
		(2 "B.Cu" signal)
		(9 "F.Adhes" user "F.Adhesive")
		(11 "B.Adhes" user "B.Adhesive")
		(13 "F.Paste" user)
		(15 "B.Paste" user)
		(5 "F.SilkS" user "F.Silkscreen")
		(7 "B.SilkS" user "B.Silkscreen")
		(1 "F.Mask" user)
		(3 "B.Mask" user)
		(17 "Dwgs.User" user "User.Drawings")
		(19 "Cmts.User" user "User.Comments")
		(21 "Eco1.User" user "User.Eco1")
		(23 "Eco2.User" user "User.Eco2")
		(25 "Edge.Cuts" user)
		(27 "Margin" user)
		(31 "F.CrtYd" user "F.Courtyard")
		(29 "B.CrtYd" user "B.Courtyard")
		(35 "F.Fab" user)
		(33 "B.Fab" user)
	)
	(footprint "antmicro-footprints:TP_SMD_1mm"
		(layer "B.Cu")
		(at 75.74 74.55 -90)
		(property "Reference" "TP34"
			(at -1.06 4.51 90)
			(layer "B.SilkS")
			(effects
				(font
					(size 0.7 0.7)
					(thickness 0.15)
				)
				(justify left bottom mirror)
			)
		)
		(property "Value" "TP_1mm_SMD"
			(at 0 -1.4 90)
			(layer "B.Fab")
			(hide yes)
			(effects
				(font
					(size 0.7 0.7)
					(thickness 0.15)
				)
				(justify left bottom mirror)
			)
		)
		(property "Description" "Test point 1mm SMD"
			(at 0 0 90)
			(layer "B.Fab")
			(hide yes)
			(effects
				(font
					(size 1.27 1.27)
					(thickness 0.15)
				)
				(justify mirror)
			)
		)
		(property "MPN" ""
			(at 0 0 90)
			(unlocked yes)
			(layer "B.Fab")
			(hide yes)
			(effects
				(font
					(size 1 1)
					(thickness 0.15)
				)
				(justify mirror)
			)
		)
		(property "Manufacturer" ""
			(at 0 0 90)
			(unlocked yes)
			(layer "B.Fab")
			(hide yes)
			(effects
				(font
					(size 1 1)
					(thickness 0.15)
				)
				(justify mirror)
			)
		)
		(property "Author" "Antmicro"
			(at 0 0 90)
			(unlocked yes)
			(layer "B.Fab")
			(hide yes)
			(effects
				(font
					(size 1 1)
					(thickness 0.15)
				)
				(justify mirror)
			)
		)
		(property "License" "Apache-2.0"
			(at 0 0 90)
			(unlocked yes)
			(layer "B.Fab")
			(hide yes)
			(effects
				(font
					(size 1 1)
					(thickness 0.15)
				)
				(justify mirror)
			)
		)
		(sheetname "/Power/")
		(sheetfile "power.kicad_sch")
		(attr exclude_from_pos_files exclude_from_bom)
		(fp_circle
			(center 0 0)
			(end 0.6 0)
			(stroke
				(width 0.05)
				(type default)
			)
			(fill no)
			(layer "B.CrtYd")
		)
		(pad "1" smd circle
			(at 0 0 270)
			(size 1 1)
			(layers "B.Cu" "B.Mask")
			(net 6 "DVDD")
			(pinfunction "1")
			(pintype "passive")
		)
	)
	(footprint "antmicro-footprints:C_0402_1005Metric"
		(layer "B.Cu")
		(at 79.4 105.08 90)
		(descr "Capacitor SMD 0402")
		(tags "capacitor SMD 0402")
		(property "Reference" "C83"
			(at -11.81 0.0225 90)
			(layer "B.SilkS")
			(effects
				(font
					(size 0.7 0.7)
					(thickness 0.15)
				)
				(justify right top mirror)
			)
		)
		(property "Value" "C_1u_25V_0402"
			(at -1.022927 -2.155213 90)
			(layer "B.Fab")
			(hide yes)
			(effects
				(font
					(size 0.7 0.7)
					(thickness 0.15)
				)
				(justify right top mirror)
			)
		)
		(property "Datasheet" "https://www.murata.com/products/productdetail?partno=GRM155R61E105KE11%23"
			(at 0 0 90)
			(layer "B.Fab")
			(hide yes)
			(effects
				(font
					(size 1.27 1.27)
					(thickness 0.15)
				)
				(justify mirror)
			)
		)
		(property "Description" "SMD Multilayer Ceramic Capacitor, 1 µF, 25 V, 0402 [1005 Metric], ± 10%, X5R, GRM Series"
			(at 0 0 90)
			(layer "B.Fab")
			(hide yes)
			(effects
				(font
					(size 1.27 1.27)
					(thickness 0.15)
				)
				(justify mirror)
			)
		)
		(property "MPN" "GRM155R61E105KE11J"
			(at 0 0 90)
			(unlocked yes)
			(layer "B.Fab")
			(hide yes)
			(effects
				(font
					(size 1 1)
					(thickness 0.15)
				)
				(justify mirror)
			)
		)
		(property "Manufacturer" "Murata"
			(at 0 0 90)
			(unlocked yes)
			(layer "B.Fab")
			(hide yes)
			(effects
				(font
					(size 1 1)
					(thickness 0.15)
				)
				(justify mirror)
			)
		)
		(property "License" "Apache-2.0"
			(at 0 0 90)
			(unlocked yes)
			(layer "B.Fab")
			(hide yes)
			(effects
				(font
					(size 1 1)
					(thickness 0.15)
				)
				(justify mirror)
			)
		)
		(property "Author" "Antmicro"
			(at 0 0 90)
			(unlocked yes)
			(layer "B.Fab")
			(hide yes)
			(effects
				(font
					(size 1 1)
					(thickness 0.15)
				)
				(justify mirror)
			)
		)
		(property "Val" "1u"
			(at 0 0 90)
			(unlocked yes)
			(layer "B.Fab")
			(hide yes)
			(effects
				(font
					(size 1 1)
					(thickness 0.15)
				)
				(justify mirror)
			)
		)
		(property "Voltage" "25V"
			(at 0 0 90)
			(unlocked yes)
			(layer "B.Fab")
			(hide yes)
			(effects
				(font
					(size 1 1)
					(thickness 0.15)
				)
				(justify mirror)
			)
		)
		(property "Dielectric" "X5R"
			(at 0 0 90)
			(unlocked yes)
			(layer "B.Fab")
			(hide yes)
			(effects
				(font
					(size 1 1)
					(thickness 0.15)
				)
				(justify mirror)
			)
		)
		(sheetname "/X710-AT2 power/")
		(sheetfile "x710-at2-power.kicad_sch")
		(attr smd)
		(fp_rect
			(start -0.925 0.47)
			(end 0.925 -0.47)
			(stroke
				(width 0.05)
				(type default)
			)
			(fill no)
			(layer "B.CrtYd")
		)
		(fp_line
			(start 0.504 -0.248)
			(end -0.494 -0.248)
			(stroke
				(width 0.15)
				(type solid)
			)
			(layer "B.Fab")
		)
		(fp_line
			(start -0.494 -0.248)
			(end -0.494 0.25)
			(stroke
				(width 0.15)
				(type solid)
			)
			(layer "B.Fab")
		)
		(fp_line
			(start 0.504 0.25)
			(end 0.504 -0.248)
			(stroke
				(width 0.15)
				(type solid)
			)
			(layer "B.Fab")
		)
		(fp_line
			(start -0.494 0.25)
			(end 0.504 0.25)
			(stroke
				(width 0.15)
				(type solid)
			)
			(layer "B.Fab")
		)
		(pad "1" smd roundrect
			(at -0.48 0 90)
			(size 0.59 0.64)
			(layers "B.Cu" "B.Mask" "B.Paste")
			(roundrect_rratio 0.25)
			(net 28 "GND")
			(pintype "passive")
		)
		(pad "2" smd roundrect
			(at 0.48 0 90)
			(size 0.59 0.64)
			(layers "B.Cu" "B.Mask" "B.Paste")
			(roundrect_rratio 0.25)
			(net 6 "DVDD")
			(pintype "passive")
		)
	)
	(footprint "antmicro-footprints:C_0402_1005Metric"
		(layer "B.Cu")
		(at 75.79 107.9 -90)
		(descr "Capacitor SMD 0402")
		(tags "capacitor SMD 0402")
		(property "Reference" "C168"
			(at 0.84 -0.33 90)
			(layer "B.SilkS")
			(effects
				(font
					(size 0.7 0.7)
					(thickness 0.15)
				)
				(justify left bottom mirror)
			)
		)
		(property "Value" "C_1u_25V_0402"
			(at -1.022927 -2.155213 90)
			(layer "B.Fab")
			(hide yes)
			(effects
				(font
					(size 0.7 0.7)
					(thickness 0.15)
				)
				(justify left bottom mirror)
			)
		)
		(property "Datasheet" "https://www.murata.com/products/productdetail?partno=GRM155R61E105KE11%23"
			(at 0 0 90)
			(layer "B.Fab")
			(hide yes)
			(effects
				(font
					(size 1.27 1.27)
					(thickness 0.15)
				)
				(justify mirror)
			)
		)
		(property "Description" "SMD Multilayer Ceramic Capacitor, 1 µF, 25 V, 0402 [1005 Metric], ± 10%, X5R, GRM Series"
			(at 0 0 90)
			(layer "B.Fab")
			(hide yes)
			(effects
				(font
					(size 1.27 1.27)
					(thickness 0.15)
				)
				(justify mirror)
			)
		)
		(property "MPN" "GRM155R61E105KE11J"
			(at 0 0 270)
			(unlocked yes)
			(layer "B.Fab")
			(hide yes)
			(effects
				(font
					(size 1 1)
					(thickness 0.15)
				)
				(justify mirror)
			)
		)
		(property "Manufacturer" "Murata"
			(at 0 0 270)
			(unlocked yes)
			(layer "B.Fab")
			(hide yes)
			(effects
				(font
					(size 1 1)
					(thickness 0.15)
				)
				(justify mirror)
			)
		)
		(property "License" "Apache-2.0"
			(at 0 0 270)
			(unlocked yes)
			(layer "B.Fab")
			(hide yes)
			(effects
				(font
					(size 1 1)
					(thickness 0.15)
				)
				(justify mirror)
			)
		)
		(property "Author" "Antmicro"
			(at 0 0 270)
			(unlocked yes)
			(layer "B.Fab")
			(hide yes)
			(effects
				(font
					(size 1 1)
					(thickness 0.15)
				)
				(justify mirror)
			)
		)
		(property "Val" "1u"
			(at 0 0 270)
			(unlocked yes)
			(layer "B.Fab")
			(hide yes)
			(effects
				(font
					(size 1 1)
					(thickness 0.15)
				)
				(justify mirror)
			)
		)
		(property "Voltage" "25V"
			(at 0 0 270)
			(unlocked yes)
			(layer "B.Fab")
			(hide yes)
			(effects
				(font
					(size 1 1)
					(thickness 0.15)
				)
				(justify mirror)
			)
		)
		(property "Dielectric" "X5R"
			(at 0 0 270)
			(unlocked yes)
			(layer "B.Fab")
			(hide yes)
			(effects
				(font
					(size 1 1)
					(thickness 0.15)
				)
				(justify mirror)
			)
		)
		(sheetname "/X710-AT2 power/")
		(sheetfile "x710-at2-power.kicad_sch")
		(attr smd)
		(fp_rect
			(start -0.925 0.47)
			(end 0.925 -0.47)
			(stroke
				(width 0.05)
				(type default)
			)
			(fill no)
			(layer "B.CrtYd")
		)
		(fp_line
			(start -0.494 0.25)
			(end 0.504 0.25)
			(stroke
				(width 0.15)
				(type solid)
			)
			(layer "B.Fab")
		)
		(fp_line
			(start 0.504 0.25)
			(end 0.504 -0.248)
			(stroke
				(width 0.15)
				(type solid)
			)
			(layer "B.Fab")
		)
		(fp_line
			(start -0.494 -0.248)
			(end -0.494 0.25)
			(stroke
				(width 0.15)
				(type solid)
			)
			(layer "B.Fab")
		)
		(fp_line
			(start 0.504 -0.248)
			(end -0.494 -0.248)
			(stroke
				(width 0.15)
				(type solid)
			)
			(layer "B.Fab")
		)
		(pad "1" smd roundrect
			(at -0.48 0 270)
			(size 0.59 0.64)
			(layers "B.Cu" "B.Mask" "B.Paste")
			(roundrect_rratio 0.25)
			(net 28 "GND")
			(pintype "passive")
		)
		(pad "2" smd roundrect
			(at 0.48 0 270)
			(size 0.59 0.64)
			(layers "B.Cu" "B.Mask" "B.Paste")
			(roundrect_rratio 0.25)
			(net 5 "P0_AVDDL")
			(pintype "passive")
		)
	)
	(footprint "antmicro-footprints:TP_SMD_0.75mm"
		(layer "B.Cu")
		(at 100.55 108.7)
		(property "Reference" "TP4"
			(at -0.32 2.54 90)
			(layer "B.SilkS")
			(effects
				(font
					(size 0.7 0.7)
					(thickness 0.15)
				)
				(justify right top mirror)
			)
		)
		(property "Value" "TP_0.75mm_SMD"
			(at 0 -1.2 0)
			(layer "B.Fab")
			(hide yes)
			(effects
				(font
					(size 0.7 0.7)
					(thickness 0.15)
				)
				(justify right top mirror)
			)
		)
		(property "Description" "SMT test point"
			(at 0 0 0)
			(layer "B.Fab")
			(hide yes)
			(effects
				(font
					(size 1.27 1.27)
					(thickness 0.15)
				)
				(justify mirror)
			)
		)
		(property "MPN" ""
			(at 0 0 0)
			(unlocked yes)
			(layer "B.Fab")
			(hide yes)
			(effects
				(font
					(size 1 1)
					(thickness 0.15)
				)
				(justify mirror)
			)
		)
		(property "Manufacturer" ""
			(at 0 0 0)
			(unlocked yes)
			(layer "B.Fab")
			(hide yes)
			(effects
				(font
					(size 1 1)
					(thickness 0.15)
				)
				(justify mirror)
			)
		)
		(property "Author" "Antmicro"
			(at 0 0 0)
			(unlocked yes)
			(layer "B.Fab")
			(hide yes)
			(effects
				(font
					(size 1 1)
					(thickness 0.15)
				)
				(justify mirror)
			)
		)
		(property "License" "Apache-2.0"
			(at 0 0 0)
			(unlocked yes)
			(layer "B.Fab")
			(hide yes)
			(effects
				(font
					(size 1 1)
					(thickness 0.15)
				)
				(justify mirror)
			)
		)
		(sheetname "/X710-AT2 Misc/")
		(sheetfile "x710-at2-mics.kicad_sch")
		(attr exclude_from_pos_files exclude_from_bom)
		(fp_circle
			(center 0 0)
			(end 0.475 0)
			(stroke
				(width 0.05)
				(type default)
			)
			(fill no)
			(layer "B.CrtYd")
		)
		(pad "1" smd circle
			(at 0 0)
			(size 0.75 0.75)
			(layers "B.Cu" "B.Mask")
			(net 365 "/X710-AT2 Misc/NCSI.CRS_DV")
			(pinfunction "1")
			(pintype "passive")
		)
	)
	(footprint "antmicro-footprints:C_0402_1005Metric"
		(layer "B.Cu")
		(at 60.670003 103.849999)
		(descr "Capacitor SMD 0402")
		(tags "capacitor SMD 0402")
		(property "Reference" "C27"
			(at -1.010003 0.530001 0)
			(layer "B.SilkS")
			(effects
				(font
					(size 0.7 0.7)
					(thickness 0.15)
				)
				(justify right top mirror)
			)
		)
		(property "Value" "C_100n_0402"
			(at -1.022927 -2.155213 0)
			(layer "B.Fab")
			(hide yes)
			(effects
				(font
					(size 0.7 0.7)
					(thickness 0.15)
				)
				(justify right top mirror)
			)
		)
		(property "Datasheet" "https://www.murata.com/products/productdetail?partno=GRM155R61H104KE14%23"
			(at 0 0 0)
			(layer "B.Fab")
			(hide yes)
			(effects
				(font
					(size 1.27 1.27)
					(thickness 0.15)
				)
				(justify mirror)
			)
		)
		(property "Description" "SMD Multilayer Ceramic Capacitor, 0.1 µF, 50 V, 0402 [1005 Metric], ± 10%, X5R, GRM Series"
			(at 0 0 0)
			(layer "B.Fab")
			(hide yes)
			(effects
				(font
					(size 1.27 1.27)
					(thickness 0.15)
				)
				(justify mirror)
			)
		)
		(property "MPN" "GRM155R61H104KE14D"
			(at 0 0 0)
			(unlocked yes)
			(layer "B.Fab")
			(hide yes)
			(effects
				(font
					(size 1 1)
					(thickness 0.15)
				)
				(justify mirror)
			)
		)
		(property "Manufacturer" "Murata"
			(at 0 0 0)
			(unlocked yes)
			(layer "B.Fab")
			(hide yes)
			(effects
				(font
					(size 1 1)
					(thickness 0.15)
				)
				(justify mirror)
			)
		)
		(property "License" "Apache-2.0"
			(at 0 0 0)
			(unlocked yes)
			(layer "B.Fab")
			(hide yes)
			(effects
				(font
					(size 1 1)
					(thickness 0.15)
				)
				(justify mirror)
			)
		)
		(property "Author" "Antmicro"
			(at 0 0 0)
			(unlocked yes)
			(layer "B.Fab")
			(hide yes)
			(effects
				(font
					(size 1 1)
					(thickness 0.15)
				)
				(justify mirror)
			)
		)
		(property "Val" "100n"
			(at 0 0 0)
			(unlocked yes)
			(layer "B.Fab")
			(hide yes)
			(effects
				(font
					(size 1 1)
					(thickness 0.15)
				)
				(justify mirror)
			)
		)
		(property "Voltage" "50V"
			(at 0 0 0)
			(unlocked yes)
			(layer "B.Fab")
			(hide yes)
			(effects
				(font
					(size 1 1)
					(thickness 0.15)
				)
				(justify mirror)
			)
		)
		(property "Dielectric" "X5R"
			(at 0 0 0)
			(unlocked yes)
			(layer "B.Fab")
			(hide yes)
			(effects
				(font
					(size 1 1)
					(thickness 0.15)
				)
				(justify mirror)
			)
		)
		(sheetname "/Power/")
		(sheetfile "power.kicad_sch")
		(attr smd)
		(fp_rect
			(start -0.925 0.47)
			(end 0.925 -0.47)
			(stroke
				(width 0.05)
				(type default)
			)
			(fill no)
			(layer "B.CrtYd")
		)
		(fp_line
			(start -0.494 -0.248)
			(end -0.494 0.25)
			(stroke
				(width 0.15)
				(type solid)
			)
			(layer "B.Fab")
		)
		(fp_line
			(start -0.494 0.25)
			(end 0.504 0.25)
			(stroke
				(width 0.15)
				(type solid)
			)
			(layer "B.Fab")
		)
		(fp_line
			(start 0.504 -0.248)
			(end -0.494 -0.248)
			(stroke
				(width 0.15)
				(type solid)
			)
			(layer "B.Fab")
		)
		(fp_line
			(start 0.504 0.25)
			(end 0.504 -0.248)
			(stroke
				(width 0.15)
				(type solid)
			)
			(layer "B.Fab")
		)
		(pad "1" smd roundrect
			(at -0.48 0)
			(size 0.59 0.64)
			(layers "B.Cu" "B.Mask" "B.Paste")
			(roundrect_rratio 0.25)
			(net 28 "GND")
			(pintype "passive")
		)
		(pad "2" smd roundrect
			(at 0.48 0)
			(size 0.59 0.64)
			(layers "B.Cu" "B.Mask" "B.Paste")
			(roundrect_rratio 0.25)
			(net 310 "/Power/+1V88_OUT")
			(pintype "passive")
		)
	)
	(footprint "antmicro-footprints:R_0402_1005Metric"
		(layer "B.Cu")
		(at 95.225 94 -90)
		(descr "Resistor SMD 0402")
		(tags "resistor SMD 0402")
		(property "Reference" "R138"
			(at -1.4 -0.575 90)
			(layer "B.SilkS")
			(effects
				(font
					(size 0.7 0.7)
					(thickness 0.15)
				)
				(justify left top mirror)
			)
		)
		(property "Value" "R_100R_0402"
			(at -1.011843 -1.772046 90)
			(layer "B.Fab")
			(hide yes)
			(effects
				(font
					(size 0.7 0.7)
					(thickness 0.15)
				)
				(justify left bottom mirror)
			)
		)
		(property "Datasheet" "https://www.bourns.com/docs/product-datasheets/cr.pdf"
			(at 0 0 90)
			(layer "B.Fab")
			(hide yes)
			(effects
				(font
					(size 1.27 1.27)
					(thickness 0.15)
				)
				(justify mirror)
			)
		)
		(property "Description" "SMD Chip Resistor, 100 ohm, ± 1%, 62.5 mW, 0402 [1005 Metric], Thick Film, General Purpose"
			(at 0 0 90)
			(layer "B.Fab")
			(hide yes)
			(effects
				(font
					(size 1.27 1.27)
					(thickness 0.15)
				)
				(justify mirror)
			)
		)
		(property "MPN" "CR0402-FX-1000GLF"
			(at 0 0 270)
			(unlocked yes)
			(layer "B.Fab")
			(hide yes)
			(effects
				(font
					(size 1 1)
					(thickness 0.15)
				)
				(justify mirror)
			)
		)
		(property "Manufacturer" "Bourns"
			(at 0 0 270)
			(unlocked yes)
			(layer "B.Fab")
			(hide yes)
			(effects
				(font
					(size 1 1)
					(thickness 0.15)
				)
				(justify mirror)
			)
		)
		(property "License" "Apache-2.0"
			(at 0 0 270)
			(unlocked yes)
			(layer "B.Fab")
			(hide yes)
			(effects
				(font
					(size 1 1)
					(thickness 0.15)
				)
				(justify mirror)
			)
		)
		(property "Author" "Antmicro"
			(at 0 0 270)
			(unlocked yes)
			(layer "B.Fab")
			(hide yes)
			(effects
				(font
					(size 1 1)
					(thickness 0.15)
				)
				(justify mirror)
			)
		)
		(property "Val" "100R"
			(at 0 0 270)
			(unlocked yes)
			(layer "B.Fab")
			(hide yes)
			(effects
				(font
					(size 1 1)
					(thickness 0.15)
				)
				(justify mirror)
			)
		)
		(property "Tolerance" "1%"
			(at 0 0 270)
			(unlocked yes)
			(layer "B.Fab")
			(hide yes)
			(effects
				(font
					(size 1 1)
					(thickness 0.15)
				)
				(justify mirror)
			)
		)
		(sheetname "/X710-AT2 RSVD/")
		(sheetfile "x710-at2-rsvd.kicad_sch")
		(attr smd)
		(fp_rect
			(start -0.925 0.47)
			(end 0.925 -0.47)
			(stroke
				(width 0.05)
				(type default)
			)
			(fill no)
			(layer "B.CrtYd")
		)
		(fp_rect
			(start -0.5 0.25)
			(end 0.5 -0.25)
			(stroke
				(width 0.15)
				(type solid)
			)
			(fill no)
			(layer "B.Fab")
		)
		(pad "1" smd roundrect
			(at -0.48 0 270)
			(size 0.59 0.64)
			(layers "B.Cu" "B.Mask" "B.Paste")
			(roundrect_rratio 0.25)
			(net 28 "GND")
			(pintype "passive")
		)
		(pad "2" smd roundrect
			(at 0.48 0 270)
			(size 0.59 0.64)
			(layers "B.Cu" "B.Mask" "B.Paste")
			(roundrect_rratio 0.25)
			(net 126 "/X710-AT2 RSVD/RSVDW1_VSS")
			(pintype "passive")
		)
	)
)
